(kicad_pcb
	(version 20260206)
	(generator "pcbnew")
	(generator_version "10.0")
	(general
		(thickness 1.21888)
		(legacy_teardrops no)
	)
	(paper "A4")
	(title_block
		(title "timecard-v9 — TimeCard-DC-V9_EXP.PcbDoc")
		(comment 1 "Time Appliance Project (Time Card) / footprints 65-69 of 402")
	)
	(layers
		(0 "F.Cu" signal "TOP")
		(4 "In1.Cu" signal "SGND")
		(6 "In2.Cu" signal "IN1")
		(8 "In3.Cu" signal "IN2")
		(10 "In4.Cu" signal "SGND1")
		(2 "B.Cu" signal "BOTTOM")
		(9 "F.Adhes" user "F.Adhesive")
		(11 "B.Adhes" user "B.Adhesive")
		(13 "F.Paste" user "Top Paste")
		(15 "B.Paste" user "Bottom Paste")
		(5 "F.SilkS" user "Top Overlay")
		(7 "B.SilkS" user "Bottom Overlay")
		(1 "F.Mask" user "Top Solder")
		(3 "B.Mask" user "Bottom Solder")
		(17 "Dwgs.User" user "User.Drawings")
		(19 "Cmts.User" user "User.Comments")
		(21 "Eco1.User" user "User.Eco1")
		(23 "Eco2.User" user "User.Eco2")
		(25 "Edge.Cuts" user)
		(27 "Margin" user)
		(31 "F.CrtYd" user "Top Courtyard")
		(29 "B.CrtYd" user "Bottom Courtyard")
		(35 "F.Fab" user "Top Component Center")
		(33 "B.Fab" user "Bottom Component Center")
	)
	(footprint "Vault:RESC1005X40X25LL05T10"
		(layer "F.Cu")
		(at 193.2216 120.0162 -90)
		(property "Reference" "R167"
			(at -2.60321 -0.126921 90)
			(unlocked yes)
			(layer "F.SilkS")
			(effects
				(font
					(size 0.762 0.762)
					(thickness 0.2032)
				)
			)
		)
		(property "Value" "DNI_49.9_1%_0402"
			(at -2.579871 11.71832 180)
			(unlocked yes)
			(layer "F.SilkS")
			(hide yes)
			(effects
				(font
					(size 0.762 0.762)
					(thickness 0.2032)
				)
			)
		)
		(sheetname "11-M2_RCB_MUX")
		(sheetfile "11-M2_RCB_MUX.kicad_sch")
		(duplicate_pad_numbers_are_jumpers no)
		(pad "1" smd rect
			(at -0.375 0)
			(size 0.45 0.5)
			(layers "F.Cu" "F.Mask" "F.Paste")
			(net "GPS2_PIN11")
		)
		(pad "2" smd rect
			(at 0.375 0)
			(size 0.45 0.5)
			(layers "F.Cu" "F.Mask" "F.Paste")
			(net "M2_GPS2_PIN11")
		)
	)
	(footprint "Vault:FP-0402-L_1_0_1-W_0_5_0_1-IPC_C"
		(layer "F.Cu")
		(at 75.1216 104.2162 180)
		(property "Reference" "C26"
			(at 2.4714 -0.026931 0)
			(unlocked yes)
			(layer "F.SilkS")
			(effects
				(font
					(size 0.762 0.762)
					(thickness 0.2286)
				)
			)
		)
		(property "Value" "0.1uF_25V_0402"
			(at 2.069035 2.567191 180)
			(unlocked yes)
			(layer "F.SilkS")
			(hide yes)
			(effects
				(font
					(size 0.762 0.762)
					(thickness 0.2286)
				)
			)
		)
		(sheetname "01-USER_IO")
		(sheetfile "01-USER_IO.kicad_sch")
		(duplicate_pad_numbers_are_jumpers no)
		(fp_line
			(start 0.65607 0.7)
			(end -0.65607 0.7)
			(stroke
				(width 0.2)
				(type solid)
			)
			(layer "F.SilkS")
		)
		(fp_line
			(start 0.65607 -0.7)
			(end -0.65607 -0.7)
			(stroke
				(width 0.2)
				(type solid)
			)
			(layer "F.SilkS")
		)
		(fp_line
			(start 0.75607 0.4)
			(end -0.75606 0.4)
			(stroke
				(width 0.2)
				(type solid)
			)
			(layer "F.CrtYd")
		)
		(fp_line
			(start 0.75607 -0.4)
			(end 0.75607 0.4)
			(stroke
				(width 0.2)
				(type solid)
			)
			(layer "F.CrtYd")
		)
		(fp_line
			(start 0.75607 -0.4)
			(end -0.75606 -0.4)
			(stroke
				(width 0.2)
				(type solid)
			)
			(layer "F.CrtYd")
		)
		(fp_line
			(start -0.75606 -0.4)
			(end -0.75606 0.4)
			(stroke
				(width 0.2)
				(type solid)
			)
			(layer "F.CrtYd")
		)
		(fp_line
			(start 0.75607 0.4)
			(end -0.75606 0.4)
			(stroke
				(width 0.2)
				(type solid)
			)
			(layer "F.Fab")
		)
		(fp_line
			(start 0.75607 -0.4)
			(end 0.75607 0.4)
			(stroke
				(width 0.2)
				(type solid)
			)
			(layer "F.Fab")
		)
		(fp_line
			(start 0.75607 -0.4)
			(end -0.75606 -0.4)
			(stroke
				(width 0.2)
				(type solid)
			)
			(layer "F.Fab")
		)
		(fp_line
			(start 0.5 0)
			(end -0.5 0)
			(stroke
				(width 0.1)
				(type solid)
			)
			(layer "F.Fab")
		)
		(fp_line
			(start 0 -0.5)
			(end 0 0.5)
			(stroke
				(width 0.1)
				(type solid)
			)
			(layer "F.Fab")
		)
		(fp_line
			(start -0.75606 -0.4)
			(end -0.75606 0.4)
			(stroke
				(width 0.2)
				(type solid)
			)
			(layer "F.Fab")
		)
		(fp_text user "${REFERENCE}"
			(at -0.00001 0.09602 180)
			(unlocked yes)
			(layer "F.Fab")
			(effects
				(font
					(face "Arial")
					(size 0.63 0.63)
					(thickness 0.1)
				)
				(justify left bottom)
			)
		)
		(pad "1" smd rect
			(at -0.36553 0 180)
			(size 0.58106 0.51213)
			(layers "F.Cu" "F.Mask" "F.Paste")
			(net "+3.3V")
			(solder_mask_margin 0)
			(solder_paste_margin 0)
		)
		(pad "2" smd rect
			(at 0.36554 0 180)
			(size 0.58106 0.51213)
			(layers "F.Cu" "F.Mask" "F.Paste")
			(net "GND")
			(solder_mask_margin 0)
			(solder_paste_margin 0)
		)
	)
	(footprint "Vault:RESC1005X40X25NL05T05"
		(layer "F.Cu")
		(at 156.7216 131.5162 90)
		(property "Reference" "R87"
			(at -1.6714 0.326931 90)
			(unlocked yes)
			(layer "F.SilkS")
			(effects
				(font
					(size 0.762 0.762)
					(thickness 0.2286)
				)
			)
		)
		(property "Value" "27_1%_0402"
			(at -2.732271 7.37632 0)
			(unlocked yes)
			(layer "F.SilkS")
			(hide yes)
			(effects
				(font
					(size 0.762 0.762)
					(thickness 0.2286)
				)
			)
		)
		(sheetname "09-USBUart_PPSMUX_UARTMUX")
		(sheetfile "09-USBUart_PPSMUX_UARTMUX.kicad_sch")
		(duplicate_pad_numbers_are_jumpers no)
		(pad "1" smd rect
			(at -0.45 0 180)
			(size 0.55 0.55)
			(layers "F.Cu" "F.Mask" "F.Paste")
			(net "FTDI_TX")
		)
		(pad "2" smd rect
			(at 0.45 0 180)
			(size 0.55 0.55)
			(layers "F.Cu" "F.Mask" "F.Paste")
			(net "NetR87_2")
		)
	)
	(footprint "Vault:FP-ABS07-MFG"
		(layer "F.Cu")
		(at 118.48072 86.4662 90)
		(property "Reference" "Y1"
			(at 0.153195 -1.776719 90)
			(unlocked yes)
			(layer "F.SilkS")
			(effects
				(font
					(size 0.762 0.762)
					(thickness 0.2032)
				)
			)
		)
		(property "Value" "ABS07-32.768KHZ-T"
			(at 11.032235 2.706871 90)
			(unlocked yes)
			(layer "F.SilkS")
			(hide yes)
			(effects
				(font
					(size 0.762 0.762)
					(thickness 0.2032)
				)
			)
		)
		(sheetname "05-GPS_IMU_SENSORS")
		(sheetfile "05-GPS_IMU_SENSORS.kicad_sch")
		(duplicate_pad_numbers_are_jumpers no)
		(fp_line
			(start -0.325 -0.8)
			(end 0.325 -0.8)
			(stroke
				(width 0.2)
				(type solid)
			)
			(layer "F.SilkS")
		)
		(fp_line
			(start -0.325 0.8)
			(end 0.325 0.8)
			(stroke
				(width 0.2)
				(type solid)
			)
			(layer "F.SilkS")
		)
		(fp_line
			(start 1.9 -1.05)
			(end 1.9 1.05)
			(stroke
				(width 0.2)
				(type solid)
			)
			(layer "F.CrtYd")
		)
		(fp_line
			(start -1.9 -1.05)
			(end 1.9 -1.05)
			(stroke
				(width 0.2)
				(type solid)
			)
			(layer "F.CrtYd")
		)
		(fp_line
			(start -1.9 -1.05)
			(end -1.9 1.05)
			(stroke
				(width 0.2)
				(type solid)
			)
			(layer "F.CrtYd")
		)
		(fp_line
			(start -1.9 1.05)
			(end 1.9 1.05)
			(stroke
				(width 0.2)
				(type solid)
			)
			(layer "F.CrtYd")
		)
		(fp_line
			(start 1.9 -1.05)
			(end 1.9 1.05)
			(stroke
				(width 0.2)
				(type solid)
			)
			(layer "F.Fab")
		)
		(fp_line
			(start -1.9 -1.05)
			(end 1.9 -1.05)
			(stroke
				(width 0.2)
				(type solid)
			)
			(layer "F.Fab")
		)
		(fp_line
			(start -1.9 -1.05)
			(end -1.9 1.05)
			(stroke
				(width 0.2)
				(type solid)
			)
			(layer "F.Fab")
		)
		(fp_line
			(start 0 -0.5)
			(end 0 0.5)
			(stroke
				(width 0.1)
				(type solid)
			)
			(layer "F.Fab")
		)
		(fp_line
			(start -0.5 0)
			(end 0.5 0)
			(stroke
				(width 0.1)
				(type solid)
			)
			(layer "F.Fab")
		)
		(fp_line
			(start -1.9 1.05)
			(end 1.9 1.05)
			(stroke
				(width 0.2)
				(type solid)
			)
			(layer "F.Fab")
		)
		(fp_text user "${REFERENCE}"
			(at 0.00091 0.10711 90)
			(unlocked yes)
			(layer "F.Fab")
			(effects
				(font
					(face "Arial")
					(size 0.63 0.63)
					(thickness 0.1)
				)
				(justify left bottom)
			)
		)
		(pad "1" smd rect
			(at -1.25 0 90)
			(size 1.1 1.9)
			(layers "F.Cu" "F.Mask" "F.Paste")
			(net "BNO_XOUT32")
			(solder_mask_margin 0)
			(solder_paste_margin 0)
		)
		(pad "2" smd rect
			(at 1.25 0 90)
			(size 1.1 1.9)
			(layers "F.Cu" "F.Mask" "F.Paste")
			(net "BNO_XIN32")
			(solder_mask_margin 0)
			(solder_paste_margin 0)
		)
	)
	(footprint "Capacitors:CAPC2012X14N"
		(layer "F.Cu")
		(at 229.8216 65.1162 90)
		(property "Reference" "C1"
			(at 1.9 0.393345 90)
			(unlocked yes)
			(layer "F.SilkS")
			(effects
				(font
					(size 0.762 0.762)
					(thickness 0.2286)
				)
				(justify left bottom)
			)
		)
		(property "Value" "CAP_0805_10UF_25V"
			(at -0.433445 1.2125 0)
			(unlocked yes)
			(layer "F.SilkS")
			(hide yes)
			(effects
				(font
					(size 0.762 0.762)
					(thickness 0.2286)
				)
				(justify left bottom)
			)
		)
		(sheetname "03-POWER")
		(sheetfile "03-POWER.kicad_sch")
		(duplicate_pad_numbers_are_jumpers no)
		(fp_line
			(start -0.762 -0.9652)
			(end 0.762 -0.9652)
			(stroke
				(width 0.1524)
				(type solid)
			)
			(layer "F.SilkS")
		)
		(fp_line
			(start -0.762 0.9652)
			(end 0.762 0.9652)
			(stroke
				(width 0.1524)
				(type solid)
			)
			(layer "F.SilkS")
		)
		(pad "1" smd rect
			(at -0.9 0 180)
			(size 1.45 1.15)
			(layers "F.Cu" "F.Mask" "F.Paste")
			(net "+12V")
		)
		(pad "2" smd rect
			(at 0.9 0 180)
			(size 1.45 1.15)
			(layers "F.Cu" "F.Mask" "F.Paste")
			(net "GND")
		)
	)
)
